# SCM (Grand Teton) — schematic netlist excerpt (pin names and nets, part order shuffled) for the footprints in the layout excerpt that follows; sources: Cadence DE-HDL packaged netlist, KiCad conversion of 12092022_DA0F0TMDCD0_F0T_Management_Board_D_brd_V3_OCP.brd

R287  Q_RES  499 1% CHIP  pkg 0402LF  page 22 : A = P3V3_RGM ; B = RST_BMC_EXTRST_R2_N
PR526  Q_RES  12.4K 1% CHIP  pkg 0402LF  page 51 : A = P5V_AUX_FB ; B = GND

(kicad_pcb
	(version 20260206)
	(generator "pcbnew")
	(generator_version "10.0")
	(general
		(thickness 1.6)
		(legacy_teardrops no)
	)
	(paper "A4")
	(title_block
		(title "12092022_DA0F0TMDCD0_F0T_Management_Board_D_brd_V3_OCP.brd")
		(comment 1 "Grand Teton / footprints 515-516 of 1440")
	)
	(layers
		(0 "F.Cu" signal "TOP")
		(4 "In1.Cu" signal "GND")
		(6 "In2.Cu" signal "IN1")
		(8 "In3.Cu" signal "GND1")
		(10 "In4.Cu" signal "IN2")
		(12 "In5.Cu" signal "VCC")
		(14 "In6.Cu" signal "VCC1")
		(16 "In7.Cu" signal "IN3")
		(18 "In8.Cu" signal "GND2")
		(20 "In9.Cu" signal "IN4")
		(22 "In10.Cu" signal "GND3")
		(2 "B.Cu" signal "BOTTOM")
		(9 "F.Adhes" user "F.Adhesive")
		(11 "B.Adhes" user "B.Adhesive")
		(13 "F.Paste" user "Package Geometry/Pastemask Top")
		(15 "B.Paste" user "Package Geometry/Pastemask Bottom")
		(5 "F.SilkS" user "Ref Des/Silkscreen Top")
		(7 "B.SilkS" user "Ref Des/Silkscreen Bottom")
		(1 "F.Mask" user "Board Geometry/Soldermask Top")
		(3 "B.Mask" user "Board Geometry/Soldermask Bottom")
		(17 "Dwgs.User" user "User.Drawings")
		(19 "Cmts.User" user "User.Comments")
		(21 "Eco1.User" user "User.Eco1")
		(23 "Eco2.User" user "User.Eco2")
		(25 "Edge.Cuts" user "Board Geometry/Outline")
		(27 "Margin" user)
		(31 "F.CrtYd" user "Package Geometry/Place Bound Top")
		(29 "B.CrtYd" user "Package Geometry/Place Bound Bottom")
		(35 "F.Fab" user "Ref Des/Assembly Top")
		(33 "B.Fab" user "Ref Des/Assembly Bottom")
	)
	(footprint ""
		(layer "F.Cu")
		(at 10.767568 -50.110898 -90)
		(property "Reference" "PR526"
			(at 0 0 270)
			(layer "F.SilkS")
			(hide yes)
			(effects
				(font
					(size 1.27 1.27)
				)
			)
		)
		(property "Value" ""
			(at 0 0 270)
			(layer "F.Fab")
			(effects
				(font
					(size 1.27 1.27)
				)
			)
		)
		(duplicate_pad_numbers_are_jumpers no)
		(fp_line
			(start -0.7874 0.4064)
			(end -0.7874 -0.4064)
			(stroke
				(width 0.1524)
				(type default)
			)
			(layer "F.SilkS")
		)
		(fp_line
			(start 0.7874 0.4064)
			(end -0.7874 0.4064)
			(stroke
				(width 0.1524)
				(type default)
			)
			(layer "F.SilkS")
		)
		(fp_line
			(start -0.7874 -0.4064)
			(end 0.7874 -0.4064)
			(stroke
				(width 0.1524)
				(type default)
			)
			(layer "F.SilkS")
		)
		(fp_line
			(start 0.7874 -0.4064)
			(end 0.7874 0.4064)
			(stroke
				(width 0.1524)
				(type default)
			)
			(layer "F.SilkS")
		)
		(fp_line
			(start -0.67945 0.3048)
			(end -0.67945 -0.305054)
			(stroke
				(width 0.1)
				(type default)
			)
			(layer "F.Fab")
		)
		(fp_line
			(start -0.12065 0.3048)
			(end -0.67945 0.3048)
			(stroke
				(width 0.1)
				(type default)
			)
			(layer "F.Fab")
		)
		(fp_line
			(start 0.120396 0.3048)
			(end 0.120396 0.2794)
			(stroke
				(width 0.1)
				(type default)
			)
			(layer "F.Fab")
		)
		(fp_line
			(start 0.67945 0.3048)
			(end 0.120396 0.3048)
			(stroke
				(width 0.1)
				(type default)
			)
			(layer "F.Fab")
		)
		(fp_line
			(start -0.12065 0.2794)
			(end -0.12065 0.3048)
			(stroke
				(width 0.1)
				(type default)
			)
			(layer "F.Fab")
		)
		(fp_line
			(start 0.120396 0.2794)
			(end -0.12065 0.2794)
			(stroke
				(width 0.1)
				(type default)
			)
			(layer "F.Fab")
		)
		(fp_line
			(start -0.12065 -0.2794)
			(end 0.12065 -0.2794)
			(stroke
				(width 0.1)
				(type default)
			)
			(layer "F.Fab")
		)
		(fp_line
			(start 0.12065 -0.2794)
			(end 0.12065 -0.3048)
			(stroke
				(width 0.1)
				(type default)
			)
			(layer "F.Fab")
		)
		(fp_line
			(start 0.12065 -0.3048)
			(end 0.67945 -0.3048)
			(stroke
				(width 0.1)
				(type default)
			)
			(layer "F.Fab")
		)
		(fp_line
			(start 0.67945 -0.3048)
			(end 0.67945 0.3048)
			(stroke
				(width 0.1)
				(type default)
			)
			(layer "F.Fab")
		)
		(fp_line
			(start -0.67945 -0.305054)
			(end -0.12065 -0.305054)
			(stroke
				(width 0.1)
				(type default)
			)
			(layer "F.Fab")
		)
		(fp_line
			(start -0.12065 -0.305054)
			(end -0.12065 -0.2794)
			(stroke
				(width 0.1)
				(type default)
			)
			(layer "F.Fab")
		)
		(pad "1" smd circle
			(at -0.40005 0 270)
			(size 0 0)
			(layers "F.Cu" "F.Mask" "F.Paste")
			(net "P5V_AUX_FB")
		)
		(pad "2" smd circle
			(at 0.40005 0 270)
			(size 0 0)
			(layers "F.Cu" "F.Mask" "F.Paste")
			(net "GND")
		)
	)
	(footprint ""
		(layer "F.Cu")
		(at 49.2125 -98.298 90)
		(property "Reference" "R287"
			(at 0 0 90)
			(layer "F.SilkS")
			(hide yes)
			(effects
				(font
					(size 1.27 1.27)
				)
			)
		)
		(property "Value" ""
			(at 0 0 90)
			(layer "F.Fab")
			(effects
				(font
					(size 1.27 1.27)
				)
			)
		)
		(duplicate_pad_numbers_are_jumpers no)
		(fp_line
			(start 0.7874 -0.4064)
			(end 0.7874 0.4064)
			(stroke
				(width 0.1524)
				(type default)
			)
			(layer "F.SilkS")
		)
		(fp_line
			(start -0.7874 -0.4064)
			(end 0.7874 -0.4064)
			(stroke
				(width 0.1524)
				(type default)
			)
			(layer "F.SilkS")
		)
		(fp_line
			(start 0.7874 0.4064)
			(end -0.7874 0.4064)
			(stroke
				(width 0.1524)
				(type default)
			)
			(layer "F.SilkS")
		)
		(fp_line
			(start -0.7874 0.4064)
			(end -0.7874 -0.4064)
			(stroke
				(width 0.1524)
				(type default)
			)
			(layer "F.SilkS")
		)
		(fp_line
			(start -0.12065 -0.305054)
			(end -0.12065 -0.2794)
			(stroke
				(width 0.1)
				(type default)
			)
			(layer "F.Fab")
		)
		(fp_line
			(start -0.67945 -0.305054)
			(end -0.12065 -0.305054)
			(stroke
				(width 0.1)
				(type default)
			)
			(layer "F.Fab")
		)
		(fp_line
			(start 0.67945 -0.3048)
			(end 0.67945 0.3048)
			(stroke
				(width 0.1)
				(type default)
			)
			(layer "F.Fab")
		)
		(fp_line
			(start 0.12065 -0.3048)
			(end 0.67945 -0.3048)
			(stroke
				(width 0.1)
				(type default)
			)
			(layer "F.Fab")
		)
		(fp_line
			(start 0.12065 -0.2794)
			(end 0.12065 -0.3048)
			(stroke
				(width 0.1)
				(type default)
			)
			(layer "F.Fab")
		)
		(fp_line
			(start -0.12065 -0.2794)
			(end 0.12065 -0.2794)
			(stroke
				(width 0.1)
				(type default)
			)
			(layer "F.Fab")
		)
		(fp_line
			(start 0.120396 0.2794)
			(end -0.12065 0.2794)
			(stroke
				(width 0.1)
				(type default)
			)
			(layer "F.Fab")
		)
		(fp_line
			(start -0.12065 0.2794)
			(end -0.12065 0.3048)
			(stroke
				(width 0.1)
				(type default)
			)
			(layer "F.Fab")
		)
		(fp_line
			(start 0.67945 0.3048)
			(end 0.120396 0.3048)
			(stroke
				(width 0.1)
				(type default)
			)
			(layer "F.Fab")
		)
		(fp_line
			(start 0.120396 0.3048)
			(end 0.120396 0.2794)
			(stroke
				(width 0.1)
				(type default)
			)
			(layer "F.Fab")
		)
		(fp_line
			(start -0.12065 0.3048)
			(end -0.67945 0.3048)
			(stroke
				(width 0.1)
				(type default)
			)
			(layer "F.Fab")
		)
		(fp_line
			(start -0.67945 0.3048)
			(end -0.67945 -0.305054)
			(stroke
				(width 0.1)
				(type default)
			)
			(layer "F.Fab")
		)
		(pad "1" smd circle
			(at -0.40005 0 90)
			(size 0 0)
			(layers "F.Cu" "F.Mask" "F.Paste")
			(net "P3V3_RGM")
		)
		(pad "2" smd circle
			(at 0.40005 0 90)
			(size 0 0)
			(layers "F.Cu" "F.Mask" "F.Paste")
			(net "RST_BMC_EXTRST_R2_N")
		)
	)
)
